(kicad_pcb
	(version 20260206)
	(generator "pcbnew")
	(generator_version "10.0")
	(general
		(thickness 1.6)
		(legacy_teardrops no)
	)
	(paper "A4")
	(title_block
		(title "01162023_DA0F0TEBIF0_F0T_Expander_BD_F_brd_V02_OCP.brd")
		(comment 1 "Grand Teton / footprints 3239-3244 of 9728")
	)
	(layers
		(0 "F.Cu" signal "TOP")
		(4 "In1.Cu" signal "GND")
		(6 "In2.Cu" signal "VCC")
		(8 "In3.Cu" signal "VCC1")
		(10 "In4.Cu" signal "GND1")
		(12 "In5.Cu" signal "IN1")
		(14 "In6.Cu" signal "GND2")
		(16 "In7.Cu" signal "IN2")
		(18 "In8.Cu" signal "GND3")
		(20 "In9.Cu" signal "IN3")
		(22 "In10.Cu" signal "GND4")
		(24 "In11.Cu" signal "IN4")
		(26 "In12.Cu" signal "GND5")
		(28 "In13.Cu" signal "IN5")
		(30 "In14.Cu" signal "GND6")
		(32 "In15.Cu" signal "IN6")
		(34 "In16.Cu" signal "GND7")
		(2 "B.Cu" signal "BOTTOM")
		(9 "F.Adhes" user "F.Adhesive")
		(11 "B.Adhes" user "B.Adhesive")
		(13 "F.Paste" user "Package Geometry/Pastemask Top")
		(15 "B.Paste" user "Package Geometry/Pastemask Bottom")
		(5 "F.SilkS" user "Ref Des/Silkscreen Top")
		(7 "B.SilkS" user "Ref Des/Silkscreen Bottom")
		(1 "F.Mask" user "Board Geometry/Soldermask Top")
		(3 "B.Mask" user "Board Geometry/Soldermask Bottom")
		(17 "Dwgs.User" user "User.Drawings")
		(19 "Cmts.User" user "User.Comments")
		(21 "Eco1.User" user "User.Eco1")
		(23 "Eco2.User" user "User.Eco2")
		(25 "Edge.Cuts" user "Board Geometry/Outline")
		(27 "Margin" user)
		(31 "F.CrtYd" user "Package Geometry/Place Bound Top")
		(29 "B.CrtYd" user "Package Geometry/Place Bound Bottom")
		(35 "F.Fab" user "Ref Des/Assembly Top")
		(33 "B.Fab" user "Ref Des/Assembly Bottom")
	)
	(footprint ""
		(layer "F.Cu")
		(at 342.555322 -35.876738)
		(property "Reference" "R6104"
			(at 0 0 0)
			(layer "F.SilkS")
			(hide yes)
			(effects
				(font
					(size 1.27 1.27)
				)
			)
		)
		(property "Value" ""
			(at 0 0 0)
			(layer "F.Fab")
			(effects
				(font
					(size 1.27 1.27)
				)
			)
		)
		(duplicate_pad_numbers_are_jumpers no)
		(fp_line
			(start -0.7874 -0.4064)
			(end 0.7874 -0.4064)
			(stroke
				(width 0.1524)
				(type default)
			)
			(layer "F.SilkS")
		)
		(fp_line
			(start -0.7874 0.4064)
			(end -0.7874 -0.4064)
			(stroke
				(width 0.1524)
				(type default)
			)
			(layer "F.SilkS")
		)
		(fp_line
			(start 0.7874 -0.4064)
			(end 0.7874 0.4064)
			(stroke
				(width 0.1524)
				(type default)
			)
			(layer "F.SilkS")
		)
		(fp_line
			(start 0.7874 0.4064)
			(end -0.7874 0.4064)
			(stroke
				(width 0.1524)
				(type default)
			)
			(layer "F.SilkS")
		)
		(fp_line
			(start -0.67945 -0.305054)
			(end -0.12065 -0.305054)
			(stroke
				(width 0.1)
				(type default)
			)
			(layer "F.Fab")
		)
		(fp_line
			(start -0.67945 0.3048)
			(end -0.67945 -0.305054)
			(stroke
				(width 0.1)
				(type default)
			)
			(layer "F.Fab")
		)
		(fp_line
			(start -0.12065 -0.305054)
			(end -0.12065 -0.2794)
			(stroke
				(width 0.1)
				(type default)
			)
			(layer "F.Fab")
		)
		(fp_line
			(start -0.12065 -0.2794)
			(end 0.12065 -0.2794)
			(stroke
				(width 0.1)
				(type default)
			)
			(layer "F.Fab")
		)
		(fp_line
			(start -0.12065 0.2794)
			(end -0.12065 0.3048)
			(stroke
				(width 0.1)
				(type default)
			)
			(layer "F.Fab")
		)
		(fp_line
			(start -0.12065 0.3048)
			(end -0.67945 0.3048)
			(stroke
				(width 0.1)
				(type default)
			)
			(layer "F.Fab")
		)
		(fp_line
			(start 0.120396 0.2794)
			(end -0.12065 0.2794)
			(stroke
				(width 0.1)
				(type default)
			)
			(layer "F.Fab")
		)
		(fp_line
			(start 0.120396 0.3048)
			(end 0.120396 0.2794)
			(stroke
				(width 0.1)
				(type default)
			)
			(layer "F.Fab")
		)
		(fp_line
			(start 0.12065 -0.3048)
			(end 0.67945 -0.3048)
			(stroke
				(width 0.1)
				(type default)
			)
			(layer "F.Fab")
		)
		(fp_line
			(start 0.12065 -0.2794)
			(end 0.12065 -0.3048)
			(stroke
				(width 0.1)
				(type default)
			)
			(layer "F.Fab")
		)
		(fp_line
			(start 0.67945 -0.3048)
			(end 0.67945 0.3048)
			(stroke
				(width 0.1)
				(type default)
			)
			(layer "F.Fab")
		)
		(fp_line
			(start 0.67945 0.3048)
			(end 0.120396 0.3048)
			(stroke
				(width 0.1)
				(type default)
			)
			(layer "F.Fab")
		)
		(pad "1" smd circle
			(at -0.40005 0)
			(size 0 0)
			(layers "F.Cu" "F.Mask" "F.Paste")
			(net "P3V3_AUX")
		)
		(pad "2" smd circle
			(at 0.40005 0)
			(size 0 0)
			(layers "F.Cu" "F.Mask" "F.Paste")
			(net "PWRGD_P3V3_SSD12_D")
		)
	)
	(footprint ""
		(layer "F.Cu")
		(at 258.535932 -207.021684)
		(property "Reference" "R4902"
			(at 0 0 0)
			(layer "F.SilkS")
			(hide yes)
			(effects
				(font
					(size 1.27 1.27)
				)
			)
		)
		(property "Value" ""
			(at 0 0 0)
			(layer "F.Fab")
			(effects
				(font
					(size 1.27 1.27)
				)
			)
		)
		(duplicate_pad_numbers_are_jumpers no)
		(fp_line
			(start -0.7874 -0.4064)
			(end 0.7874 -0.4064)
			(stroke
				(width 0.1524)
				(type default)
			)
			(layer "F.SilkS")
		)
		(fp_line
			(start -0.7874 0.4064)
			(end -0.7874 -0.4064)
			(stroke
				(width 0.1524)
				(type default)
			)
			(layer "F.SilkS")
		)
		(fp_line
			(start 0.7874 -0.4064)
			(end 0.7874 0.4064)
			(stroke
				(width 0.1524)
				(type default)
			)
			(layer "F.SilkS")
		)
		(fp_line
			(start 0.7874 0.4064)
			(end -0.7874 0.4064)
			(stroke
				(width 0.1524)
				(type default)
			)
			(layer "F.SilkS")
		)
		(fp_line
			(start -0.67945 -0.305054)
			(end -0.12065 -0.305054)
			(stroke
				(width 0.1)
				(type default)
			)
			(layer "F.Fab")
		)
		(fp_line
			(start -0.67945 0.3048)
			(end -0.67945 -0.305054)
			(stroke
				(width 0.1)
				(type default)
			)
			(layer "F.Fab")
		)
		(fp_line
			(start -0.12065 -0.305054)
			(end -0.12065 -0.2794)
			(stroke
				(width 0.1)
				(type default)
			)
			(layer "F.Fab")
		)
		(fp_line
			(start -0.12065 -0.2794)
			(end 0.12065 -0.2794)
			(stroke
				(width 0.1)
				(type default)
			)
			(layer "F.Fab")
		)
		(fp_line
			(start -0.12065 0.2794)
			(end -0.12065 0.3048)
			(stroke
				(width 0.1)
				(type default)
			)
			(layer "F.Fab")
		)
		(fp_line
			(start -0.12065 0.3048)
			(end -0.67945 0.3048)
			(stroke
				(width 0.1)
				(type default)
			)
			(layer "F.Fab")
		)
		(fp_line
			(start 0.120396 0.2794)
			(end -0.12065 0.2794)
			(stroke
				(width 0.1)
				(type default)
			)
			(layer "F.Fab")
		)
		(fp_line
			(start 0.120396 0.3048)
			(end 0.120396 0.2794)
			(stroke
				(width 0.1)
				(type default)
			)
			(layer "F.Fab")
		)
		(fp_line
			(start 0.12065 -0.3048)
			(end 0.67945 -0.3048)
			(stroke
				(width 0.1)
				(type default)
			)
			(layer "F.Fab")
		)
		(fp_line
			(start 0.12065 -0.2794)
			(end 0.12065 -0.3048)
			(stroke
				(width 0.1)
				(type default)
			)
			(layer "F.Fab")
		)
		(fp_line
			(start 0.67945 -0.3048)
			(end 0.67945 0.3048)
			(stroke
				(width 0.1)
				(type default)
			)
			(layer "F.Fab")
		)
		(fp_line
			(start 0.67945 0.3048)
			(end 0.120396 0.3048)
			(stroke
				(width 0.1)
				(type default)
			)
			(layer "F.Fab")
		)
		(pad "1" smd circle
			(at -0.40005 0)
			(size 0 0)
			(layers "F.Cu" "F.Mask" "F.Paste")
			(net "JTAG_FPGA_TDO")
		)
		(pad "2" smd circle
			(at 0.40005 0)
			(size 0 0)
			(layers "F.Cu" "F.Mask" "F.Paste")
			(net "JTAG_CONN_TDO")
		)
	)
	(footprint ""
		(layer "F.Cu")
		(at 131.63296 -114.933476)
		(property "Reference" "PU101"
			(at -2.39649 3.529076 90)
			(unlocked yes)
			(layer "F.SilkS")
			(effects
				(font
					(size 0.7874 0.5842)
					(thickness 0.1524)
				)
			)
		)
		(property "Value" ""
			(at 0 0 0)
			(layer "F.Fab")
			(effects
				(font
					(size 1.27 1.27)
				)
			)
		)
		(duplicate_pad_numbers_are_jumpers no)
		(fp_line
			(start -1.239774 -1.495298)
			(end 1.239774 -1.495298)
			(stroke
				(width 0.1524)
				(type default)
			)
			(layer "F.SilkS")
		)
		(fp_line
			(start -1.239774 1.495298)
			(end -1.239774 -1.495298)
			(stroke
				(width 0.1524)
				(type default)
			)
			(layer "F.SilkS")
		)
		(fp_line
			(start 1.239774 -1.495298)
			(end 1.239774 1.495298)
			(stroke
				(width 0.1524)
				(type default)
			)
			(layer "F.SilkS")
		)
		(fp_line
			(start 1.239774 1.495298)
			(end -1.239774 1.495298)
			(stroke
				(width 0.1524)
				(type default)
			)
			(layer "F.SilkS")
		)
		(fp_poly
			(pts
				(xy -1.83007 -1.771142) (xy -2.548382 -1.05283) (xy -1.470914 -0.693674)
			)
			(stroke
				(width 0)
				(type default)
			)
			(fill yes)
			(layer "F.SilkS")
		)
		(fp_line
			(start -0.8001 -1.050036)
			(end 0.8001 -1.050036)
			(stroke
				(width 0.1)
				(type default)
			)
			(layer "F.Fab")
		)
		(fp_line
			(start -0.8001 1.050036)
			(end -0.8001 -1.050036)
			(stroke
				(width 0.1)
				(type default)
			)
			(layer "F.Fab")
		)
		(fp_line
			(start 0.8001 -1.050036)
			(end 0.8001 1.050036)
			(stroke
				(width 0.1)
				(type default)
			)
			(layer "F.Fab")
		)
		(fp_line
			(start 0.8001 1.050036)
			(end -0.8001 1.050036)
			(stroke
				(width 0.1)
				(type default)
			)
			(layer "F.Fab")
		)
		(fp_poly
			(pts
				(xy -2.458974 -0.508) (xy -2.458974 0.508) (xy -1.442974 0)
			)
			(stroke
				(width 0)
				(type default)
			)
			(fill yes)
			(layer "F.Fab")
		)
		(pad "1_2" smd circle
			(at -0.374904 0 90)
			(size 0 0)
			(layers "F.Cu" "F.Mask" "F.Paste")
			(net "P3V3_AUX")
		)
		(pad "3" smd rect
			(at -0.499872 0.999998)
			(size 0.254 0.7112)
			(layers "F.Cu" "F.Mask" "F.Paste")
			(net "GND")
		)
		(pad "4" smd rect
			(at 0 0.999998)
			(size 0.254 0.7112)
			(layers "F.Cu" "F.Mask" "F.Paste")
			(net "P3V3_NIC2_CO_ILIMIT")
		)
		(pad "5" smd rect
			(at 0.499872 0.999998)
			(size 0.254 0.7112)
			(layers "F.Cu" "F.Mask" "F.Paste")
			(net "P3V3_NIC2_CO_MODE")
		)
		(pad "6_7" smd circle
			(at 0.374904 0 270)
			(size 0 0)
			(layers "F.Cu" "F.Mask" "F.Paste")
			(net "P3V3_NIC2")
		)
		(pad "8" smd rect
			(at 0.499872 -0.999998)
			(size 0.254 0.7112)
			(layers "F.Cu" "F.Mask" "F.Paste")
			(net "P3V3_NIC2_CO_GATE")
		)
		(pad "9" smd rect
			(at 0 -0.999998)
			(size 0.254 0.7112)
			(layers "F.Cu" "F.Mask" "F.Paste")
			(net "P3V3_NIC2_CO_EN")
		)
		(pad "10" smd rect
			(at -0.499872 -0.999998)
			(size 0.254 0.7112)
			(layers "F.Cu" "F.Mask" "F.Paste")
			(net "P3V3_NIC2_CO_DV_DT")
		)
	)
	(footprint ""
		(layer "F.Cu")
		(at 219.202 -193.04)
		(property "Reference" "R1530"
			(at 0 0 0)
			(layer "F.SilkS")
			(hide yes)
			(effects
				(font
					(size 1.27 1.27)
				)
			)
		)
		(property "Value" ""
			(at 0 0 0)
			(layer "F.Fab")
			(effects
				(font
					(size 1.27 1.27)
				)
			)
		)
		(duplicate_pad_numbers_are_jumpers no)
		(fp_line
			(start -0.7874 -0.4064)
			(end 0.7874 -0.4064)
			(stroke
				(width 0.1524)
				(type default)
			)
			(layer "F.SilkS")
		)
		(fp_line
			(start -0.7874 0.4064)
			(end -0.7874 -0.4064)
			(stroke
				(width 0.1524)
				(type default)
			)
			(layer "F.SilkS")
		)
		(fp_line
			(start 0.7874 -0.4064)
			(end 0.7874 0.4064)
			(stroke
				(width 0.1524)
				(type default)
			)
			(layer "F.SilkS")
		)
		(fp_line
			(start 0.7874 0.4064)
			(end -0.7874 0.4064)
			(stroke
				(width 0.1524)
				(type default)
			)
			(layer "F.SilkS")
		)
		(fp_line
			(start -0.67945 -0.305054)
			(end -0.12065 -0.305054)
			(stroke
				(width 0.1)
				(type default)
			)
			(layer "F.Fab")
		)
		(fp_line
			(start -0.67945 0.3048)
			(end -0.67945 -0.305054)
			(stroke
				(width 0.1)
				(type default)
			)
			(layer "F.Fab")
		)
		(fp_line
			(start -0.12065 -0.305054)
			(end -0.12065 -0.2794)
			(stroke
				(width 0.1)
				(type default)
			)
			(layer "F.Fab")
		)
		(fp_line
			(start -0.12065 -0.2794)
			(end 0.12065 -0.2794)
			(stroke
				(width 0.1)
				(type default)
			)
			(layer "F.Fab")
		)
		(fp_line
			(start -0.12065 0.2794)
			(end -0.12065 0.3048)
			(stroke
				(width 0.1)
				(type default)
			)
			(layer "F.Fab")
		)
		(fp_line
			(start -0.12065 0.3048)
			(end -0.67945 0.3048)
			(stroke
				(width 0.1)
				(type default)
			)
			(layer "F.Fab")
		)
		(fp_line
			(start 0.120396 0.2794)
			(end -0.12065 0.2794)
			(stroke
				(width 0.1)
				(type default)
			)
			(layer "F.Fab")
		)
		(fp_line
			(start 0.120396 0.3048)
			(end 0.120396 0.2794)
			(stroke
				(width 0.1)
				(type default)
			)
			(layer "F.Fab")
		)
		(fp_line
			(start 0.12065 -0.3048)
			(end 0.67945 -0.3048)
			(stroke
				(width 0.1)
				(type default)
			)
			(layer "F.Fab")
		)
		(fp_line
			(start 0.12065 -0.2794)
			(end 0.12065 -0.3048)
			(stroke
				(width 0.1)
				(type default)
			)
			(layer "F.Fab")
		)
		(fp_line
			(start 0.67945 -0.3048)
			(end 0.67945 0.3048)
			(stroke
				(width 0.1)
				(type default)
			)
			(layer "F.Fab")
		)
		(fp_line
			(start 0.67945 0.3048)
			(end 0.120396 0.3048)
			(stroke
				(width 0.1)
				(type default)
			)
			(layer "F.Fab")
		)
		(pad "1" smd circle
			(at -0.40005 0)
			(size 0 0)
			(layers "F.Cu" "F.Mask" "F.Paste")
			(net "SMB_NIC7_LS_R_SCL")
		)
		(pad "2" smd circle
			(at 0.40005 0)
			(size 0 0)
			(layers "F.Cu" "F.Mask" "F.Paste")
			(net "P3V3_NIC7")
		)
	)
	(footprint ""
		(layer "F.Cu")
		(at 277.698454 -66.32194 -90)
		(property "Reference" "PC863"
			(at 0 0 270)
			(layer "F.SilkS")
			(hide yes)
			(effects
				(font
					(size 1.27 1.27)
				)
			)
		)
		(property "Value" ""
			(at 0 0 270)
			(layer "F.Fab")
			(effects
				(font
					(size 1.27 1.27)
				)
			)
		)
		(duplicate_pad_numbers_are_jumpers no)
		(fp_line
			(start -0.7874 0.4064)
			(end -0.7874 -0.4064)
			(stroke
				(width 0.1524)
				(type default)
			)
			(layer "F.SilkS")
		)
		(fp_line
			(start 0.7874 0.4064)
			(end -0.7874 0.4064)
			(stroke
				(width 0.1524)
				(type default)
			)
			(layer "F.SilkS")
		)
		(fp_line
			(start -0.7874 -0.4064)
			(end 0.7874 -0.4064)
			(stroke
				(width 0.1524)
				(type default)
			)
			(layer "F.SilkS")
		)
		(fp_line
			(start 0.7874 -0.4064)
			(end 0.7874 0.4064)
			(stroke
				(width 0.1524)
				(type default)
			)
			(layer "F.SilkS")
		)
		(fp_line
			(start -0.67945 0.3048)
			(end -0.67945 -0.305054)
			(stroke
				(width 0.1)
				(type default)
			)
			(layer "F.Fab")
		)
		(fp_line
			(start -0.12065 0.3048)
			(end -0.67945 0.3048)
			(stroke
				(width 0.1)
				(type default)
			)
			(layer "F.Fab")
		)
		(fp_line
			(start 0.120396 0.3048)
			(end 0.120396 0.2794)
			(stroke
				(width 0.1)
				(type default)
			)
			(layer "F.Fab")
		)
		(fp_line
			(start 0.67945 0.3048)
			(end 0.120396 0.3048)
			(stroke
				(width 0.1)
				(type default)
			)
			(layer "F.Fab")
		)
		(fp_line
			(start -0.12065 0.2794)
			(end -0.12065 0.3048)
			(stroke
				(width 0.1)
				(type default)
			)
			(layer "F.Fab")
		)
		(fp_line
			(start 0.120396 0.2794)
			(end -0.12065 0.2794)
			(stroke
				(width 0.1)
				(type default)
			)
			(layer "F.Fab")
		)
		(fp_line
			(start -0.12065 -0.2794)
			(end 0.12065 -0.2794)
			(stroke
				(width 0.1)
				(type default)
			)
			(layer "F.Fab")
		)
		(fp_line
			(start 0.12065 -0.2794)
			(end 0.12065 -0.3048)
			(stroke
				(width 0.1)
				(type default)
			)
			(layer "F.Fab")
		)
		(fp_line
			(start 0.12065 -0.3048)
			(end 0.67945 -0.3048)
			(stroke
				(width 0.1)
				(type default)
			)
			(layer "F.Fab")
		)
		(fp_line
			(start 0.67945 -0.3048)
			(end 0.67945 0.3048)
			(stroke
				(width 0.1)
				(type default)
			)
			(layer "F.Fab")
		)
		(fp_line
			(start -0.67945 -0.305054)
			(end -0.12065 -0.305054)
			(stroke
				(width 0.1)
				(type default)
			)
			(layer "F.Fab")
		)
		(fp_line
			(start -0.12065 -0.305054)
			(end -0.12065 -0.2794)
			(stroke
				(width 0.1)
				(type default)
			)
			(layer "F.Fab")
		)
		(pad "1" smd circle
			(at -0.40005 0 270)
			(size 0 0)
			(layers "F.Cu" "F.Mask" "F.Paste")
			(net "P12V_SSD9_CO_GATE")
		)
		(pad "2" smd circle
			(at 0.40005 0 270)
			(size 0 0)
			(layers "F.Cu" "F.Mask" "F.Paste")
			(net "GND")
		)
	)
	(footprint ""
		(layer "F.Cu")
		(at 401.762468 -22.937216 90)
		(property "Reference" "R1726"
			(at 0 0 90)
			(layer "F.SilkS")
			(hide yes)
			(effects
				(font
					(size 1.27 1.27)
				)
			)
		)
		(property "Value" ""
			(at 0 0 90)
			(layer "F.Fab")
			(effects
				(font
					(size 1.27 1.27)
				)
			)
		)
		(duplicate_pad_numbers_are_jumpers no)
		(fp_line
			(start 0.7874 -0.4064)
			(end 0.7874 0.4064)
			(stroke
				(width 0.1524)
				(type default)
			)
			(layer "F.SilkS")
		)
		(fp_line
			(start -0.7874 -0.4064)
			(end 0.7874 -0.4064)
			(stroke
				(width 0.1524)
				(type default)
			)
			(layer "F.SilkS")
		)
		(fp_line
			(start 0.7874 0.4064)
			(end -0.7874 0.4064)
			(stroke
				(width 0.1524)
				(type default)
			)
			(layer "F.SilkS")
		)
		(fp_line
			(start -0.7874 0.4064)
			(end -0.7874 -0.4064)
			(stroke
				(width 0.1524)
				(type default)
			)
			(layer "F.SilkS")
		)
		(fp_line
			(start -0.12065 -0.305054)
			(end -0.12065 -0.2794)
			(stroke
				(width 0.1)
				(type default)
			)
			(layer "F.Fab")
		)
		(fp_line
			(start -0.67945 -0.305054)
			(end -0.12065 -0.305054)
			(stroke
				(width 0.1)
				(type default)
			)
			(layer "F.Fab")
		)
		(fp_line
			(start 0.67945 -0.3048)
			(end 0.67945 0.3048)
			(stroke
				(width 0.1)
				(type default)
			)
			(layer "F.Fab")
		)
		(fp_line
			(start 0.12065 -0.3048)
			(end 0.67945 -0.3048)
			(stroke
				(width 0.1)
				(type default)
			)
			(layer "F.Fab")
		)
		(fp_line
			(start 0.12065 -0.2794)
			(end 0.12065 -0.3048)
			(stroke
				(width 0.1)
				(type default)
			)
			(layer "F.Fab")
		)
		(fp_line
			(start -0.12065 -0.2794)
			(end 0.12065 -0.2794)
			(stroke
				(width 0.1)
				(type default)
			)
			(layer "F.Fab")
		)
		(fp_line
			(start 0.120396 0.2794)
			(end -0.12065 0.2794)
			(stroke
				(width 0.1)
				(type default)
			)
			(layer "F.Fab")
		)
		(fp_line
			(start -0.12065 0.2794)
			(end -0.12065 0.3048)
			(stroke
				(width 0.1)
				(type default)
			)
			(layer "F.Fab")
		)
		(fp_line
			(start 0.67945 0.3048)
			(end 0.120396 0.3048)
			(stroke
				(width 0.1)
				(type default)
			)
			(layer "F.Fab")
		)
		(fp_line
			(start 0.120396 0.3048)
			(end 0.120396 0.2794)
			(stroke
				(width 0.1)
				(type default)
			)
			(layer "F.Fab")
		)
		(fp_line
			(start -0.12065 0.3048)
			(end -0.67945 0.3048)
			(stroke
				(width 0.1)
				(type default)
			)
			(layer "F.Fab")
		)
		(fp_line
			(start -0.67945 0.3048)
			(end -0.67945 -0.305054)
			(stroke
				(width 0.1)
				(type default)
			)
			(layer "F.Fab")
		)
		(pad "1" smd circle
			(at -0.40005 0 90)
			(size 0 0)
			(layers "F.Cu" "F.Mask" "F.Paste")
			(net "SMB_BIC_I2C9_MUX1_SSD13_R_SDA")
		)
		(pad "2" smd circle
			(at 0.40005 0 90)
			(size 0 0)
			(layers "F.Cu" "F.Mask" "F.Paste")
			(net "SMB_ISO_SSD13_SDA")
		)
	)
)
